(kicad_pcb
	(version 20260206)
	(generator "pcbnew")
	(generator_version "10.0")
	(general
		(thickness 1.6)
		(legacy_teardrops no)
	)
	(paper "A4")
	(title_block
		(title "dpb — 14545-sa.0730WZS0815.brd")
		(comment 1 "Honey Badger (Wiwynn) / footprints 793-796 of 1066")
	)
	(layers
		(0 "F.Cu" signal "TOP")
		(4 "In1.Cu" signal "L2GND")
		(6 "In2.Cu" signal "L3")
		(8 "In3.Cu" signal "L4VCC")
		(10 "In4.Cu" signal "L5VCC")
		(12 "In5.Cu" signal "L6")
		(14 "In6.Cu" signal "L7GND")
		(2 "B.Cu" signal "BOTTOM")
		(9 "F.Adhes" user "F.Adhesive")
		(11 "B.Adhes" user "B.Adhesive")
		(13 "F.Paste" user "Package Geometry/Pastemask Top")
		(15 "B.Paste" user "Package Geometry/Pastemask Bottom")
		(5 "F.SilkS" user "Ref Des/Silkscreen Top")
		(7 "B.SilkS" user "Ref Des/Silkscreen Bottom")
		(1 "F.Mask" user "Board Geometry/Soldermask Top")
		(3 "B.Mask" user "Board Geometry/Soldermask Bottom")
		(17 "Dwgs.User" user "User.Drawings")
		(19 "Cmts.User" user "User.Comments")
		(21 "Eco1.User" user "User.Eco1")
		(23 "Eco2.User" user "User.Eco2")
		(25 "Edge.Cuts" user "Board Geometry/Outline")
		(27 "Margin" user)
		(31 "F.CrtYd" user "Package Geometry/Place Bound Top")
		(29 "B.CrtYd" user "Package Geometry/Place Bound Bottom")
		(35 "F.Fab" user "Ref Des/Assembly Top")
		(33 "B.Fab" user "Ref Des/Assembly Bottom")
	)
	(footprint ""
		(layer "F.Cu")
		(at 77.215746 -21.999702 -90)
		(property "Reference" "R301"
			(at 0 0 270)
			(layer "F.SilkS")
			(hide yes)
			(effects
				(font
					(size 1.27 1.27)
				)
			)
		)
		(property "Value" "4K7R2J-2-GP"
			(at 0.064008 -3.993896 270)
			(unlocked yes)
			(layer "F.Fab")
			(hide yes)
			(effects
				(font
					(size 1.016 1.016)
					(thickness 0.1524)
				)
			)
		)
		(property "Device Type" "R402H16"
			(at 0.064008 -5.517896 270)
			(unlocked yes)
			(layer "F.Fab")
			(hide yes)
			(effects
				(font
					(size 1.016 1.016)
					(thickness 0.1524)
				)
			)
		)
		(duplicate_pad_numbers_are_jumpers no)
		(fp_line
			(start -0.508 -0.9398)
			(end -0.508 0.9398)
			(stroke
				(width 0.1524)
				(type default)
			)
			(layer "F.SilkS")
		)
		(fp_line
			(start 0.508 -0.9398)
			(end -0.508 -0.9398)
			(stroke
				(width 0.1524)
				(type default)
			)
			(layer "F.SilkS")
		)
		(fp_rect
			(start -0.508 0.9398)
			(end 0.508 -0.9398)
			(stroke
				(width 0)
				(type default)
			)
			(fill no)
			(layer "F.CrtYd")
		)
		(fp_rect
			(start -0.508 0.9398)
			(end 0.508 -0.9398)
			(stroke
				(width 0)
				(type default)
			)
			(fill no)
			(layer "F.Fab")
		)
		(pad "1" smd custom
			(at 0 -0.4445 270)
			(size 0.1397 0.1397)
			(layers "F.Cu" "F.Mask" "F.Paste")
			(net "P3V3")
			(options
				(clearance outline)
				(anchor circle)
			)
			(primitives
				(gr_poly
					(pts
						(arc
							(start -0.1778 -0.2794)
							(mid -0.249642 -0.249642)
							(end -0.2794 -0.1778)
						)
						(arc
							(start -0.2794 0.1778)
							(mid -0.249642 0.249642)
							(end -0.1778 0.2794)
						)
						(arc
							(start 0.1778 0.2794)
							(mid 0.249642 0.249642)
							(end 0.2794 0.1778)
						)
						(arc
							(start 0.2794 -0.1778)
							(mid 0.249642 -0.249642)
							(end 0.1778 -0.2794)
						)
					)
					(width 0)
					(fill yes)
				)
			)
		)
		(pad "2" smd custom
			(at 0 0.4445 270)
			(size 0.1397 0.1397)
			(layers "F.Cu" "F.Mask" "F.Paste")
			(net "HDD_PRSNT_NET14")
			(options
				(clearance outline)
				(anchor circle)
			)
			(primitives
				(gr_poly
					(pts
						(arc
							(start -0.1778 -0.2794)
							(mid -0.249642 -0.249642)
							(end -0.2794 -0.1778)
						)
						(arc
							(start -0.2794 0.1778)
							(mid -0.249642 0.249642)
							(end -0.1778 0.2794)
						)
						(arc
							(start 0.1778 0.2794)
							(mid 0.249642 0.249642)
							(end 0.2794 0.1778)
						)
						(arc
							(start 0.2794 -0.1778)
							(mid 0.249642 -0.249642)
							(end 0.1778 -0.2794)
						)
					)
					(width 0)
					(fill yes)
				)
			)
		)
	)
	(footprint ""
		(layer "F.Cu")
		(at 28.447746 -298.9707 180)
		(property "Reference" "C225"
			(at 0 0 180)
			(layer "F.SilkS")
			(hide yes)
			(effects
				(font
					(size 1.27 1.27)
				)
			)
		)
		(property "Value" "SC10U25V6KX-1GP"
			(at -0.0762 -5.1308 180)
			(unlocked yes)
			(layer "F.Fab")
			(hide yes)
			(effects
				(font
					(size 1.016 1.016)
					(thickness 0.1524)
				)
			)
		)
		(property "Device Type" "C1206H71"
			(at -0.127 -6.6548 180)
			(unlocked yes)
			(layer "F.Fab")
			(hide yes)
			(effects
				(font
					(size 1.016 1.016)
					(thickness 0.1524)
				)
			)
		)
		(duplicate_pad_numbers_are_jumpers no)
		(fp_line
			(start 1.016 2.2352)
			(end -1.016 2.2352)
			(stroke
				(width 0.1524)
				(type default)
			)
			(layer "F.SilkS")
		)
		(fp_line
			(start 1.016 0.8382)
			(end 1.016 2.2352)
			(stroke
				(width 0.1524)
				(type default)
			)
			(layer "F.SilkS")
		)
		(fp_line
			(start 1.016 -2.2352)
			(end 1.016 -0.8382)
			(stroke
				(width 0.1524)
				(type default)
			)
			(layer "F.SilkS")
		)
		(fp_line
			(start -1.016 2.2352)
			(end -1.016 0.8382)
			(stroke
				(width 0.1524)
				(type default)
			)
			(layer "F.SilkS")
		)
		(fp_line
			(start -1.016 -0.8382)
			(end -1.016 -2.2352)
			(stroke
				(width 0.1524)
				(type default)
			)
			(layer "F.SilkS")
		)
		(fp_line
			(start -1.016 -2.2352)
			(end 1.016 -2.2352)
			(stroke
				(width 0.1524)
				(type default)
			)
			(layer "F.SilkS")
		)
		(fp_rect
			(start -1.0922 2.3114)
			(end 1.0922 -2.3114)
			(stroke
				(width 0)
				(type default)
			)
			(fill no)
			(layer "F.CrtYd")
		)
		(fp_poly
			(pts
				(xy 1.0922 -2.3114) (xy 1.0922 2.3114) (xy -1.0922 2.3114) (xy -1.0922 -2.3114)
			)
			(stroke
				(width 0)
				(type default)
			)
			(fill no)
			(layer "F.Fab")
		)
		(pad "1" smd rect
			(at 0 -1.397 180)
			(size 1.651 1.27)
			(layers "F.Cu" "F.Mask" "F.Paste")
			(net "P12V_HDD7")
		)
		(pad "2" smd rect
			(at 0 1.397 180)
			(size 1.651 1.27)
			(layers "F.Cu" "F.Mask" "F.Paste")
			(net "GND")
		)
	)
	(footprint ""
		(layer "F.Cu")
		(at 33.782 -306.324 90)
		(property "Reference" "R419"
			(at 0 0 90)
			(layer "F.SilkS")
			(hide yes)
			(effects
				(font
					(size 1.27 1.27)
				)
			)
		)
		(property "Value" "0R2J-2-GP"
			(at 0.064008 -3.993896 90)
			(unlocked yes)
			(layer "F.Fab")
			(hide yes)
			(effects
				(font
					(size 1.016 1.016)
					(thickness 0.1524)
				)
			)
		)
		(property "Device Type" "R402H16"
			(at 0.064008 -5.517896 90)
			(unlocked yes)
			(layer "F.Fab")
			(hide yes)
			(effects
				(font
					(size 1.016 1.016)
					(thickness 0.1524)
				)
			)
		)
		(duplicate_pad_numbers_are_jumpers no)
		(fp_line
			(start 0.508 -0.9398)
			(end -0.508 -0.9398)
			(stroke
				(width 0.1524)
				(type default)
			)
			(layer "F.SilkS")
		)
		(fp_line
			(start -0.508 -0.9398)
			(end -0.508 0.9398)
			(stroke
				(width 0.1524)
				(type default)
			)
			(layer "F.SilkS")
		)
		(fp_rect
			(start -0.508 0.9398)
			(end 0.508 -0.9398)
			(stroke
				(width 0)
				(type default)
			)
			(fill no)
			(layer "F.CrtYd")
		)
		(fp_rect
			(start -0.508 0.9398)
			(end 0.508 -0.9398)
			(stroke
				(width 0)
				(type default)
			)
			(fill no)
			(layer "F.Fab")
		)
		(pad "1" smd custom
			(at 0 -0.4445 90)
			(size 0.1397 0.1397)
			(layers "F.Cu" "F.Mask" "F.Paste")
			(net "SW_HDD11_G")
			(options
				(clearance outline)
				(anchor circle)
			)
			(primitives
				(gr_poly
					(pts
						(arc
							(start -0.1778 -0.2794)
							(mid -0.249642 -0.249642)
							(end -0.2794 -0.1778)
						)
						(arc
							(start -0.2794 0.1778)
							(mid -0.249642 0.249642)
							(end -0.1778 0.2794)
						)
						(arc
							(start 0.1778 0.2794)
							(mid 0.249642 0.249642)
							(end 0.2794 0.1778)
						)
						(arc
							(start 0.2794 -0.1778)
							(mid 0.249642 -0.249642)
							(end 0.1778 -0.2794)
						)
					)
					(width 0)
					(fill yes)
				)
			)
		)
		(pad "2" smd custom
			(at 0 0.4445 90)
			(size 0.1397 0.1397)
			(layers "F.Cu" "F.Mask" "F.Paste")
			(net "SW_HDD11_R")
			(options
				(clearance outline)
				(anchor circle)
			)
			(primitives
				(gr_poly
					(pts
						(arc
							(start -0.1778 -0.2794)
							(mid -0.249642 -0.249642)
							(end -0.2794 -0.1778)
						)
						(arc
							(start -0.2794 0.1778)
							(mid -0.249642 0.249642)
							(end -0.1778 0.2794)
						)
						(arc
							(start 0.1778 0.2794)
							(mid 0.249642 0.249642)
							(end 0.2794 0.1778)
						)
						(arc
							(start 0.2794 -0.1778)
							(mid 0.249642 -0.249642)
							(end 0.1778 -0.2794)
						)
					)
					(width 0)
					(fill yes)
				)
			)
		)
	)
	(footprint ""
		(layer "F.Cu")
		(at 234.822746 -27.9527 180)
		(property "Reference" "PR14"
			(at 0 0 180)
			(layer "F.SilkS")
			(hide yes)
			(effects
				(font
					(size 1.27 1.27)
				)
			)
		)
		(property "Value" "10KR2D-GP"
			(at 0.064008 -3.993896 180)
			(unlocked yes)
			(layer "F.Fab")
			(hide yes)
			(effects
				(font
					(size 1.016 1.016)
					(thickness 0.1524)
				)
			)
		)
		(property "Device Type" "R402H16"
			(at 0.064008 -5.517896 180)
			(unlocked yes)
			(layer "F.Fab")
			(hide yes)
			(effects
				(font
					(size 1.016 1.016)
					(thickness 0.1524)
				)
			)
		)
		(duplicate_pad_numbers_are_jumpers no)
		(fp_line
			(start 0.508 -0.9398)
			(end -0.508 -0.9398)
			(stroke
				(width 0.1524)
				(type default)
			)
			(layer "F.SilkS")
		)
		(fp_line
			(start -0.508 -0.9398)
			(end -0.508 0.9398)
			(stroke
				(width 0.1524)
				(type default)
			)
			(layer "F.SilkS")
		)
		(fp_rect
			(start -0.508 0.9398)
			(end 0.508 -0.9398)
			(stroke
				(width 0)
				(type default)
			)
			(fill no)
			(layer "F.CrtYd")
		)
		(fp_rect
			(start -0.508 0.9398)
			(end 0.508 -0.9398)
			(stroke
				(width 0)
				(type default)
			)
			(fill no)
			(layer "F.Fab")
		)
		(pad "1" smd custom
			(at 0 -0.4445 180)
			(size 0.1397 0.1397)
			(layers "F.Cu" "F.Mask" "F.Paste")
			(net "P5VA_VFB")
			(options
				(clearance outline)
				(anchor circle)
			)
			(primitives
				(gr_poly
					(pts
						(arc
							(start -0.1778 -0.2794)
							(mid -0.249642 -0.249642)
							(end -0.2794 -0.1778)
						)
						(arc
							(start -0.2794 0.1778)
							(mid -0.249642 0.249642)
							(end -0.1778 0.2794)
						)
						(arc
							(start 0.1778 0.2794)
							(mid 0.249642 0.249642)
							(end 0.2794 0.1778)
						)
						(arc
							(start 0.2794 -0.1778)
							(mid 0.249642 -0.249642)
							(end 0.1778 -0.2794)
						)
					)
					(width 0)
					(fill yes)
				)
			)
		)
		(pad "2" smd custom
			(at 0 0.4445 180)
			(size 0.1397 0.1397)
			(layers "F.Cu" "F.Mask" "F.Paste")
			(net "P5VA_AGND")
			(options
				(clearance outline)
				(anchor circle)
			)
			(primitives
				(gr_poly
					(pts
						(arc
							(start -0.1778 -0.2794)
							(mid -0.249642 -0.249642)
							(end -0.2794 -0.1778)
						)
						(arc
							(start -0.2794 0.1778)
							(mid -0.249642 0.249642)
							(end -0.1778 0.2794)
						)
						(arc
							(start 0.1778 0.2794)
							(mid 0.249642 0.249642)
							(end 0.2794 0.1778)
						)
						(arc
							(start 0.2794 -0.1778)
							(mid 0.249642 -0.249642)
							(end 0.1778 -0.2794)
						)
					)
					(width 0)
					(fill yes)
				)
			)
		)
	)
)
